(kicad_pcb
	(version 20241229)
	(generator "pcbnew")
	(generator_version "9.0")
	(general
		(thickness 1.62)
		(legacy_teardrops no)
	)
	(paper "A3")
	(title_block
		(title "COM Express 7 Baseboard")
		(date "2025-02-04")
		(rev "1.1.2")
		(company "Antmicro Ltd")
		(comment 1 "www.antmicro.com")
		(comment 9 "footprints 790-794 of 802")
	)
	(layers
		(0 "F.Cu" signal)
		(4 "In1.Cu" signal)
		(6 "In2.Cu" signal)
		(8 "In3.Cu" signal)
		(10 "In4.Cu" signal)
		(12 "In5.Cu" signal)
		(14 "In6.Cu" signal)
		(2 "B.Cu" signal)
		(9 "F.Adhes" user "F.Adhesive")
		(11 "B.Adhes" user "B.Adhesive")
		(13 "F.Paste" user)
		(15 "B.Paste" user)
		(5 "F.SilkS" user "F.Silkscreen")
		(7 "B.SilkS" user "B.Silkscreen")
		(1 "F.Mask" user)
		(3 "B.Mask" user)
		(17 "Dwgs.User" user "User.Drawings")
		(19 "Cmts.User" user "User.Comments")
		(21 "Eco1.User" user "User.Eco1")
		(23 "Eco2.User" user "User.Eco2")
		(25 "Edge.Cuts" user)
		(27 "Margin" user)
		(31 "F.CrtYd" user "F.Courtyard")
		(29 "B.CrtYd" user "B.Courtyard")
		(35 "F.Fab" user)
		(33 "B.Fab" user)
	)
	(footprint "antmicro-footprints:SOT-23-3"
		(layer "B.Cu")
		(at 101.05 71.91 90)
		(property "Reference" "Q7"
			(at 0.95 0.55 180)
			(layer "B.SilkS")
			(effects
				(font
					(size 0.7 0.7)
					(thickness 0.15)
				)
				(justify right bottom mirror)
			)
		)
		(property "Value" "BSS138-7-F"
			(at -1.9 -2.7 90)
			(layer "B.Fab")
			(effects
				(font
					(size 0.7 0.7)
					(thickness 0.15)
				)
				(justify right bottom mirror)
			)
		)
		(property "Datasheet" "https://www.diodes.com/assets/Datasheets/ds30144.pdf"
			(at 0 0 90)
			(layer "F.Fab")
			(hide yes)
			(effects
				(font
					(size 1.27 1.27)
					(thickness 0.15)
				)
			)
		)
		(property "Author" "Antmicro"
			(at 172.96 -29.14 0)
			(layer "B.Fab")
			(hide yes)
			(effects
				(font
					(size 1 1)
					(thickness 0.15)
				)
				(justify mirror)
			)
		)
		(property "License" "Apache-2.0"
			(at 172.96 -29.14 0)
			(layer "B.Fab")
			(hide yes)
			(effects
				(font
					(size 1 1)
					(thickness 0.15)
				)
				(justify mirror)
			)
		)
		(property "MPN" "BSS138-7-F"
			(at 172.96 -29.14 0)
			(layer "B.Fab")
			(hide yes)
			(effects
				(font
					(size 1 1)
					(thickness 0.15)
				)
				(justify mirror)
			)
		)
		(property "Manufacturer" "Diodes Incorporated"
			(at 172.96 -29.14 0)
			(layer "B.Fab")
			(hide yes)
			(effects
				(font
					(size 1 1)
					(thickness 0.15)
				)
				(justify mirror)
			)
		)
		(sheetname "Misc")
		(sheetfile "misc.kicad_sch")
		(attr smd)
		(fp_line
			(start 0.7 -1.5)
			(end 0.7 -0.4)
			(stroke
				(width 0.15)
				(type solid)
			)
			(layer "B.SilkS")
		)
		(fp_line
			(start -0.7 -1.5)
			(end 0.7 -1.5)
			(stroke
				(width 0.15)
				(type solid)
			)
			(layer "B.SilkS")
		)
		(fp_line
			(start -0.7 -1.35)
			(end -0.7 -1.5)
			(stroke
				(width 0.15)
				(type solid)
			)
			(layer "B.SilkS")
		)
		(fp_line
			(start -0.85 1.35)
			(end -1.45 1.35)
			(stroke
				(width 0.15)
				(type solid)
			)
			(layer "B.SilkS")
		)
		(fp_line
			(start 0.7 1.5)
			(end 0.7 0.4)
			(stroke
				(width 0.15)
				(type solid)
			)
			(layer "B.SilkS")
		)
		(fp_line
			(start -0.7 1.5)
			(end -0.85 1.35)
			(stroke
				(width 0.15)
				(type solid)
			)
			(layer "B.SilkS")
		)
		(fp_line
			(start -0.7 1.5)
			(end 0.7 1.5)
			(stroke
				(width 0.15)
				(type solid)
			)
			(layer "B.SilkS")
		)
		(fp_line
			(start 0.85 -1.65)
			(end 0.85 -0.45)
			(stroke
				(width 0.05)
				(type solid)
			)
			(layer "B.CrtYd")
		)
		(fp_line
			(start -0.85 -1.65)
			(end 0.85 -1.65)
			(stroke
				(width 0.05)
				(type solid)
			)
			(layer "B.CrtYd")
		)
		(fp_line
			(start -0.85 -1.4)
			(end -0.85 -1.65)
			(stroke
				(width 0.05)
				(type solid)
			)
			(layer "B.CrtYd")
		)
		(fp_line
			(start -1.75 -1.4)
			(end -0.85 -1.4)
			(stroke
				(width 0.05)
				(type solid)
			)
			(layer "B.CrtYd")
		)
		(fp_line
			(start -0.85 -0.5)
			(end -1.75 -0.5)
			(stroke
				(width 0.05)
				(type solid)
			)
			(layer "B.CrtYd")
		)
		(fp_line
			(start -1.75 -0.5)
			(end -1.75 -1.4)
			(stroke
				(width 0.05)
				(type solid)
			)
			(layer "B.CrtYd")
		)
		(fp_line
			(start 1.75 -0.45)
			(end 1.75 0.45)
			(stroke
				(width 0.05)
				(type solid)
			)
			(layer "B.CrtYd")
		)
		(fp_line
			(start 0.85 -0.45)
			(end 1.75 -0.45)
			(stroke
				(width 0.05)
				(type solid)
			)
			(layer "B.CrtYd")
		)
		(fp_line
			(start 1.75 0.45)
			(end 0.825 0.45)
			(stroke
				(width 0.05)
				(type solid)
			)
			(layer "B.CrtYd")
		)
		(fp_line
			(start 0.825 0.45)
			(end 0.825 1.6)
			(stroke
				(width 0.05)
				(type solid)
			)
			(layer "B.CrtYd")
		)
		(fp_line
			(start -0.85 0.5)
			(end -0.85 -0.5)
			(stroke
				(width 0.05)
				(type solid)
			)
			(layer "B.CrtYd")
		)
		(fp_line
			(start -1.75 0.5)
			(end -0.85 0.5)
			(stroke
				(width 0.05)
				(type solid)
			)
			(layer "B.CrtYd")
		)
		(fp_line
			(start -0.9 1.4)
			(end -0.9 1.6)
			(stroke
				(width 0.05)
				(type solid)
			)
			(layer "B.CrtYd")
		)
		(fp_line
			(start -1.75 1.4)
			(end -1.75 0.5)
			(stroke
				(width 0.05)
				(type solid)
			)
			(layer "B.CrtYd")
		)
		(fp_line
			(start -1.75 1.4)
			(end -0.9 1.4)
			(stroke
				(width 0.05)
				(type solid)
			)
			(layer "B.CrtYd")
		)
		(fp_line
			(start 0.825 1.6)
			(end -0.9 1.6)
			(stroke
				(width 0.05)
				(type solid)
			)
			(layer "B.CrtYd")
		)
		(fp_line
			(start -0.712 -1.523)
			(end -0.712 1.325)
			(stroke
				(width 0.15)
				(type solid)
			)
			(layer "B.Fab")
		)
		(fp_line
			(start 0.688 -1.519)
			(end -0.712 -1.519)
			(stroke
				(width 0.15)
				(type solid)
			)
			(layer "B.Fab")
		)
		(fp_line
			(start -0.712 1.325)
			(end -0.437 1.526)
			(stroke
				(width 0.15)
				(type solid)
			)
			(layer "B.Fab")
		)
		(fp_line
			(start 0.688 1.52)
			(end 0.688 -1.519)
			(stroke
				(width 0.15)
				(type solid)
			)
			(layer "B.Fab")
		)
		(fp_line
			(start 0.688 1.526)
			(end -0.437 1.526)
			(stroke
				(width 0.15)
				(type solid)
			)
			(layer "B.Fab")
		)
		(pad "1" smd roundrect
			(at -1.1 0.951 90)
			(size 1 0.6)
			(layers "B.Cu" "B.Mask" "B.Paste")
			(roundrect_rratio 0.15)
			(net 365 "/Com Express 7 MGMT/PWR_OK")
			(pinfunction "G")
			(pintype "bidirectional")
			(teardrops
				(best_length_ratio 0.2)
				(max_length 1)
				(best_width_ratio 0.9)
				(max_width 2)
				(curved_edges yes)
				(filter_ratio 0.9)
				(enabled yes)
				(allow_two_segments yes)
				(prefer_zone_connections yes)
			)
		)
		(pad "2" smd roundrect
			(at -1.1 -0.949 90)
			(size 1 0.6)
			(layers "B.Cu" "B.Mask" "B.Paste")
			(roundrect_rratio 0.15)
			(net 1 "GND")
			(pinfunction "S")
			(pintype "bidirectional")
			(teardrops
				(best_length_ratio 0.2)
				(max_length 1)
				(best_width_ratio 0.9)
				(max_width 2)
				(curved_edges yes)
				(filter_ratio 0.9)
				(enabled yes)
				(allow_two_segments yes)
				(prefer_zone_connections yes)
			)
		)
		(pad "3" smd roundrect
			(at 1.1 0.0005 90)
			(size 1 0.6)
			(layers "B.Cu" "B.Mask" "B.Paste")
			(roundrect_rratio 0.15)
			(net 539 "/Misc/~{PWR_OK}")
			(pinfunction "D")
			(pintype "bidirectional")
			(teardrops
				(best_length_ratio 0.2)
				(max_length 1)
				(best_width_ratio 0.9)
				(max_width 2)
				(curved_edges yes)
				(filter_ratio 0.9)
				(enabled yes)
				(allow_two_segments yes)
				(prefer_zone_connections yes)
			)
		)
	)
	(footprint "antmicro-footprints:C_0603_1608Metric"
		(layer "B.Cu")
		(at 303.9 79.12 -90)
		(descr "Capacitor SMD 0603")
		(tags "capacitor 0603")
		(property "Reference" "C78"
			(at -3.36 -0.45 90)
			(layer "B.SilkS")
			(effects
				(font
					(size 0.7 0.7)
					(thickness 0.15)
				)
				(justify left bottom mirror)
			)
		)
		(property "Value" "C_22u_16V_0603"
			(at -1.42757 -1.770288 90)
			(layer "B.Fab")
			(effects
				(font
					(size 0.7 0.7)
					(thickness 0.15)
				)
				(justify left bottom mirror)
			)
		)
		(property "Datasheet" "https://product.samsungsem.com/mlcc/CL10A226MO7JZN.do"
			(at 0 0 270)
			(layer "F.Fab")
			(hide yes)
			(effects
				(font
					(size 1.27 1.27)
					(thickness 0.15)
				)
			)
		)
		(property "Author" "Antmicro"
			(at 224.78 383.02 0)
			(layer "B.Fab")
			(hide yes)
			(effects
				(font
					(size 1 1)
					(thickness 0.15)
				)
				(justify mirror)
			)
		)
		(property "Dielectric" ""
			(at 224.78 383.02 0)
			(layer "B.Fab")
			(hide yes)
			(effects
				(font
					(size 1 1)
					(thickness 0.15)
				)
				(justify mirror)
			)
		)
		(property "License" "Apache-2.0"
			(at 224.78 383.02 0)
			(layer "B.Fab")
			(hide yes)
			(effects
				(font
					(size 1 1)
					(thickness 0.15)
				)
				(justify mirror)
			)
		)
		(property "MPN" "CL10A226MO7JZNC"
			(at 224.78 383.02 0)
			(layer "B.Fab")
			(hide yes)
			(effects
				(font
					(size 1 1)
					(thickness 0.15)
				)
				(justify mirror)
			)
		)
		(property "Manufacturer" "Samsung Electro-Mechanics"
			(at 224.78 383.02 0)
			(layer "B.Fab")
			(hide yes)
			(effects
				(font
					(size 1 1)
					(thickness 0.15)
				)
				(justify mirror)
			)
		)
		(property "Public" "False"
			(at 224.78 383.02 0)
			(layer "B.Fab")
			(hide yes)
			(effects
				(font
					(size 1 1)
					(thickness 0.15)
				)
				(justify mirror)
			)
		)
		(property "Val" "22u"
			(at 224.78 383.02 0)
			(layer "B.Fab")
			(hide yes)
			(effects
				(font
					(size 1 1)
					(thickness 0.15)
				)
				(justify mirror)
			)
		)
		(property "Voltage" "16V"
			(at 224.78 383.02 0)
			(layer "B.Fab")
			(hide yes)
			(effects
				(font
					(size 1 1)
					(thickness 0.15)
				)
				(justify mirror)
			)
		)
		(sheetname "M.2 key M #2")
		(sheetfile "m2keym.kicad_sch")
		(attr smd)
		(fp_line
			(start 0.15 0.4)
			(end -0.15 0.4)
			(stroke
				(width 0.15)
				(type solid)
			)
			(layer "B.SilkS")
		)
		(fp_line
			(start 0.15 -0.4)
			(end -0.15 -0.4)
			(stroke
				(width 0.15)
				(type solid)
			)
			(layer "B.SilkS")
		)
		(fp_rect
			(start -1.25 0.65)
			(end 1.25 -0.65)
			(stroke
				(width 0.05)
				(type solid)
			)
			(fill no)
			(layer "B.CrtYd")
		)
		(fp_rect
			(start -0.8 0.4)
			(end 0.8 -0.4)
			(stroke
				(width 0.15)
				(type solid)
			)
			(fill no)
			(layer "B.Fab")
		)
		(pad "1" smd roundrect
			(at -0.7 0 270)
			(size 0.8 1)
			(layers "B.Cu" "B.Mask" "B.Paste")
			(roundrect_rratio 0.2)
			(net 1 "GND")
			(pintype "passive")
			(teardrops
				(best_length_ratio 0.2)
				(max_length 1)
				(best_width_ratio 0.9)
				(max_width 2)
				(curved_edges yes)
				(filter_ratio 0.9)
				(enabled yes)
				(allow_two_segments yes)
				(prefer_zone_connections yes)
			)
		)
		(pad "2" smd roundrect
			(at 0.7 0 270)
			(size 0.8 1)
			(layers "B.Cu" "B.Mask" "B.Paste")
			(roundrect_rratio 0.2)
			(net 970 "/M.2 key M #2/M2_3V3")
			(pintype "passive")
			(teardrops
				(best_length_ratio 0.2)
				(max_length 1)
				(best_width_ratio 0.9)
				(max_width 2)
				(curved_edges yes)
				(filter_ratio 0.9)
				(enabled yes)
				(allow_two_segments yes)
				(prefer_zone_connections yes)
			)
		)
	)
	(footprint "antmicro-footprints:R_0402_1005Metric"
		(layer "B.Cu")
		(at 157.9 141.36)
		(descr "Resistor SMD 0402")
		(tags "resistor SMD 0402")
		(property "Reference" "R260"
			(at 0.85 0.45 0)
			(layer "B.SilkS")
			(effects
				(font
					(size 0.7 0.7)
					(thickness 0.15)
				)
				(justify right bottom mirror)
			)
		)
		(property "Value" "R_10k_0402"
			(at -1.011843 -1.772047 0)
			(layer "B.Fab")
			(effects
				(font
					(size 0.7 0.7)
					(thickness 0.15)
				)
				(justify right bottom mirror)
			)
		)
		(property "Datasheet" "https://www.bourns.com/docs/product-datasheets/cr.pdf"
			(at 0 0 0)
			(layer "F.Fab")
			(hide yes)
			(effects
				(font
					(size 1.27 1.27)
					(thickness 0.15)
				)
			)
		)
		(property "Author" "Antmicro"
			(at 0 0 0)
			(layer "B.Fab")
			(hide yes)
			(effects
				(font
					(size 1 1)
					(thickness 0.15)
				)
				(justify mirror)
			)
		)
		(property "License" "Apache-2.0"
			(at 0 0 0)
			(layer "B.Fab")
			(hide yes)
			(effects
				(font
					(size 1 1)
					(thickness 0.15)
				)
				(justify mirror)
			)
		)
		(property "MPN" "CR0402-FX-1002GLF"
			(at 0 0 0)
			(layer "B.Fab")
			(hide yes)
			(effects
				(font
					(size 1 1)
					(thickness 0.15)
				)
				(justify mirror)
			)
		)
		(property "Manufacturer" "Bourns"
			(at 0 0 0)
			(layer "B.Fab")
			(hide yes)
			(effects
				(font
					(size 1 1)
					(thickness 0.15)
				)
				(justify mirror)
			)
		)
		(property "Public" "False"
			(at 0 0 0)
			(layer "B.Fab")
			(hide yes)
			(effects
				(font
					(size 1 1)
					(thickness 0.15)
				)
				(justify mirror)
			)
		)
		(property "Tolerance" "1%"
			(at 0 0 0)
			(layer "B.Fab")
			(hide yes)
			(effects
				(font
					(size 1 1)
					(thickness 0.15)
				)
				(justify mirror)
			)
		)
		(property "Val" "10k"
			(at 0 0 0)
			(layer "B.Fab")
			(hide yes)
			(effects
				(font
					(size 1 1)
					(thickness 0.15)
				)
				(justify mirror)
			)
		)
		(sheetname "KR to SFI #1")
		(sheetfile "kr_sfi.kicad_sch")
		(attr smd dnp)
		(fp_rect
			(start -0.925 0.47)
			(end 0.925 -0.47)
			(stroke
				(width 0.05)
				(type default)
			)
			(fill no)
			(layer "B.CrtYd")
		)
		(fp_rect
			(start -0.5 0.25)
			(end 0.5 -0.25)
			(stroke
				(width 0.15)
				(type solid)
			)
			(fill no)
			(layer "B.Fab")
		)
		(pad "1" smd roundrect
			(at -0.48 0)
			(size 0.59 0.64)
			(layers "B.Cu" "B.Mask" "B.Paste")
			(roundrect_rratio 0.25)
			(net 655 "Net-(U43C-PRTAD0)")
			(pintype "passive")
			(teardrops
				(best_length_ratio 0.2)
				(max_length 1)
				(best_width_ratio 0.9)
				(max_width 2)
				(curved_edges yes)
				(filter_ratio 0.9)
				(enabled yes)
				(allow_two_segments yes)
				(prefer_zone_connections yes)
			)
		)
		(pad "2" smd roundrect
			(at 0.48 0)
			(size 0.59 0.64)
			(layers "B.Cu" "B.Mask" "B.Paste")
			(roundrect_rratio 0.25)
			(net 78 "+1V8")
			(pintype "passive")
			(teardrops
				(best_length_ratio 0.2)
				(max_length 1)
				(best_width_ratio 0.9)
				(max_width 2)
				(curved_edges yes)
				(filter_ratio 0.9)
				(enabled yes)
				(allow_two_segments yes)
				(prefer_zone_connections yes)
			)
		)
	)
	(footprint "antmicro-footprints:TP_SMD_0.75mm"
		(layer "B.Cu")
		(at 185.05 165.95 180)
		(property "Reference" "TP31"
			(at -0.45 3.2 90)
			(layer "B.SilkS")
			(effects
				(font
					(size 0.7 0.7)
					(thickness 0.15)
				)
				(justify left bottom mirror)
			)
		)
		(property "Value" "TP_0.75mm_SMD"
			(at 3.225 -53.865 0)
			(layer "B.Fab")
			(hide yes)
			(effects
				(font
					(size 0.7 0.7)
					(thickness 0.15)
				)
				(justify left bottom mirror)
			)
		)
		(property "Author" "Antmicro"
			(at 447.85 306.77 0)
			(layer "B.Fab")
			(hide yes)
			(effects
				(font
					(size 1 1)
					(thickness 0.15)
				)
				(justify mirror)
			)
		)
		(property "License" "Apache-2.0"
			(at 447.85 306.77 0)
			(layer "B.Fab")
			(hide yes)
			(effects
				(font
					(size 1 1)
					(thickness 0.15)
				)
				(justify mirror)
			)
		)
		(property "MPN" ""
			(at 447.85 306.77 0)
			(layer "B.Fab")
			(hide yes)
			(effects
				(font
					(size 1 1)
					(thickness 0.15)
				)
				(justify mirror)
			)
		)
		(property "Manufacturer" ""
			(at 447.85 306.77 0)
			(layer "B.Fab")
			(hide yes)
			(effects
				(font
					(size 1 1)
					(thickness 0.15)
				)
				(justify mirror)
			)
		)
		(property "Public" "False"
			(at 447.85 306.77 0)
			(layer "B.Fab")
			(hide yes)
			(effects
				(font
					(size 1 1)
					(thickness 0.15)
				)
				(justify mirror)
			)
		)
		(sheetname "Com Express 7 MGMT")
		(sheetfile "com_express_7_mgmt.kicad_sch")
		(attr exclude_from_pos_files exclude_from_bom)
		(fp_circle
			(center 0 0)
			(end 0.475 0)
			(stroke
				(width 0.05)
				(type default)
			)
			(fill no)
			(layer "B.CrtYd")
		)
		(pad "1" smd circle
			(at 0 0 180)
			(size 0.75 0.75)
			(layers "B.Cu" "B.Mask")
			(net 362 "Net-(J12D-~{SUS_STAT}{slash}~{ESPI_RESET})")
			(pinfunction "1")
			(pintype "passive")
			(teardrops
				(best_length_ratio 0.4)
				(max_length 1)
				(best_width_ratio 0.9)
				(max_width 2)
				(curved_edges yes)
				(filter_ratio 0.9)
				(enabled yes)
				(allow_two_segments yes)
				(prefer_zone_connections yes)
			)
		)
	)
	(footprint "antmicro-footprints:R_0402_1005Metric"
		(layer "B.Cu")
		(at 118.48 169.96)
		(descr "Resistor SMD 0402")
		(tags "resistor SMD 0402")
		(property "Reference" "R61"
			(at -1.13 1.35 0)
			(layer "B.SilkS")
			(effects
				(font
					(size 0.7 0.7)
					(thickness 0.15)
				)
				(justify right bottom mirror)
			)
		)
		(property "Value" "R_330R_0402"
			(at -1.011843 -1.772047 0)
			(layer "B.Fab")
			(effects
				(font
					(size 0.7 0.7)
					(thickness 0.15)
				)
				(justify right bottom mirror)
			)
		)
		(property "Datasheet" "https://www.bourns.com/docs/product-datasheets/cr.pdf"
			(at 0 0 0)
			(layer "F.Fab")
			(hide yes)
			(effects
				(font
					(size 1.27 1.27)
					(thickness 0.15)
				)
			)
		)
		(property "Author" "Antmicro"
			(at 0 0 0)
			(layer "B.Fab")
			(hide yes)
			(effects
				(font
					(size 1 1)
					(thickness 0.15)
				)
				(justify mirror)
			)
		)
		(property "License" "Apache-2.0"
			(at 0 0 0)
			(layer "B.Fab")
			(hide yes)
			(effects
				(font
					(size 1 1)
					(thickness 0.15)
				)
				(justify mirror)
			)
		)
		(property "MPN" "CR0402-FX-3300GLF"
			(at 0 0 0)
			(layer "B.Fab")
			(hide yes)
			(effects
				(font
					(size 1 1)
					(thickness 0.15)
				)
				(justify mirror)
			)
		)
		(property "Manufacturer" "Bourns"
			(at 0 0 0)
			(layer "B.Fab")
			(hide yes)
			(effects
				(font
					(size 1 1)
					(thickness 0.15)
				)
				(justify mirror)
			)
		)
		(property "Public" "False"
			(at 0 0 0)
			(layer "B.Fab")
			(hide yes)
			(effects
				(font
					(size 1 1)
					(thickness 0.15)
				)
				(justify mirror)
			)
		)
		(property "Tolerance" "1%"
			(at 0 0 0)
			(layer "B.Fab")
			(hide yes)
			(effects
				(font
					(size 1 1)
					(thickness 0.15)
				)
				(justify mirror)
			)
		)
		(property "Val" "330R"
			(at 0 0 0)
			(layer "B.Fab")
			(hide yes)
			(effects
				(font
					(size 1 1)
					(thickness 0.15)
				)
				(justify mirror)
			)
		)
		(sheetname "2xSFP+")
		(sheetfile "2xSFP+.kicad_sch")
		(attr smd)
		(fp_rect
			(start -0.925 0.47)
			(end 0.925 -0.47)
			(stroke
				(width 0.05)
				(type default)
			)
			(fill no)
			(layer "B.CrtYd")
		)
		(fp_rect
			(start -0.5 0.25)
			(end 0.5 -0.25)
			(stroke
				(width 0.15)
				(type solid)
			)
			(fill no)
			(layer "B.Fab")
		)
		(pad "1" smd roundrect
			(at -0.48 0)
			(size 0.59 0.64)
			(layers "B.Cu" "B.Mask" "B.Paste")
			(roundrect_rratio 0.25)
			(net 53 "/2xSFP+/SH")
			(pintype "passive")
			(teardrops
				(best_length_ratio 0.2)
				(max_length 1)
				(best_width_ratio 0.9)
				(max_width 2)
				(curved_edges yes)
				(filter_ratio 0.9)
				(enabled yes)
				(allow_two_segments yes)
				(prefer_zone_connections yes)
			)
		)
		(pad "2" smd roundrect
			(at 0.48 0)
			(size 0.59 0.64)
			(layers "B.Cu" "B.Mask" "B.Paste")
			(roundrect_rratio 0.25)
			(net 1 "GND")
			(pintype "passive")
			(teardrops
				(best_length_ratio 0.2)
				(max_length 1)
				(best_width_ratio 0.9)
				(max_width 2)
				(curved_edges yes)
				(filter_ratio 0.9)
				(enabled yes)
				(allow_two_segments yes)
				(prefer_zone_connections yes)
			)
		)
	)
)
